(kicad_pcb
	(version 20260206)
	(generator "pcbnew")
	(generator_version "10.0")
	(general
		(thickness 1.6)
		(legacy_teardrops no)
	)
	(paper "A4")
	(title_block
		(title "Bryce Canyon_IOM_IOC_16318-2_OCP.brd")
		(comment 1 "Bryce Canyon / footprints 601-607 of 1605")
	)
	(layers
		(0 "F.Cu" signal "TOP")
		(4 "In1.Cu" signal "L2GND")
		(6 "In2.Cu" signal "L3")
		(8 "In3.Cu" signal "L4VCC")
		(10 "In4.Cu" signal "L5VCC")
		(12 "In5.Cu" signal "L6")
		(14 "In6.Cu" signal "L7GND")
		(2 "B.Cu" signal "BOTTOM")
		(9 "F.Adhes" user "F.Adhesive")
		(11 "B.Adhes" user "B.Adhesive")
		(13 "F.Paste" user "Package Geometry/Pastemask Top")
		(15 "B.Paste" user "Package Geometry/Pastemask Bottom")
		(5 "F.SilkS" user "Ref Des/Silkscreen Top")
		(7 "B.SilkS" user "Ref Des/Silkscreen Bottom")
		(1 "F.Mask" user "Board Geometry/Soldermask Top")
		(3 "B.Mask" user "Board Geometry/Soldermask Bottom")
		(17 "Dwgs.User" user "User.Drawings")
		(19 "Cmts.User" user "User.Comments")
		(21 "Eco1.User" user "User.Eco1")
		(23 "Eco2.User" user "User.Eco2")
		(25 "Edge.Cuts" user "Board Geometry/Outline")
		(27 "Margin" user)
		(31 "F.CrtYd" user "Package Geometry/Place Bound Top")
		(29 "B.CrtYd" user "Package Geometry/Place Bound Bottom")
		(35 "F.Fab" user "Ref Des/Assembly Top")
		(33 "B.Fab" user "Ref Des/Assembly Bottom")
	)
	(footprint ""
		(layer "F.Cu")
		(at 60.452 -158.623)
		(property "Reference" "R397"
			(at 0 0 0)
			(layer "F.SilkS")
			(hide yes)
			(effects
				(font
					(size 1.27 1.27)
				)
			)
		)
		(property "Value" "4K7R2F-GP"
			(at 0.064008 -3.993896 0)
			(unlocked yes)
			(layer "F.Fab")
			(hide yes)
			(effects
				(font
					(size 1.016 1.016)
					(thickness 0.1524)
				)
			)
		)
		(property "Device Type" "R402H16"
			(at 0.064008 -5.517896 0)
			(unlocked yes)
			(layer "F.Fab")
			(hide yes)
			(effects
				(font
					(size 1.016 1.016)
					(thickness 0.1524)
				)
			)
		)
		(duplicate_pad_numbers_are_jumpers no)
		(fp_line
			(start -0.508 -0.9398)
			(end -0.508 0.9398)
			(stroke
				(width 0.1524)
				(type default)
			)
			(layer "F.SilkS")
		)
		(fp_line
			(start 0.508 -0.9398)
			(end -0.508 -0.9398)
			(stroke
				(width 0.1524)
				(type default)
			)
			(layer "F.SilkS")
		)
		(fp_rect
			(start -0.508 0.9398)
			(end 0.508 -0.9398)
			(stroke
				(width 0)
				(type default)
			)
			(fill no)
			(layer "F.CrtYd")
		)
		(fp_rect
			(start -0.508 0.9398)
			(end 0.508 -0.9398)
			(stroke
				(width 0)
				(type default)
			)
			(fill no)
			(layer "F.Fab")
		)
		(pad "1" smd custom
			(at 0 -0.4445)
			(size 0.1397 0.1397)
			(layers "F.Cu" "F.Mask" "F.Paste")
			(net "GND")
			(options
				(clearance outline)
				(anchor circle)
			)
			(primitives
				(gr_poly
					(pts
						(arc
							(start -0.1778 -0.2794)
							(mid -0.249642 -0.249642)
							(end -0.2794 -0.1778)
						)
						(arc
							(start -0.2794 0.1778)
							(mid -0.249642 0.249642)
							(end -0.1778 0.2794)
						)
						(arc
							(start 0.1778 0.2794)
							(mid 0.249642 0.249642)
							(end 0.2794 0.1778)
						)
						(arc
							(start 0.2794 -0.1778)
							(mid 0.249642 -0.249642)
							(end 0.1778 -0.2794)
						)
					)
					(width 0)
					(fill yes)
				)
			)
		)
		(pad "2" smd custom
			(at 0 0.4445)
			(size 0.1397 0.1397)
			(layers "F.Cu" "F.Mask" "F.Paste")
			(net "MAC2_TXD1")
			(options
				(clearance outline)
				(anchor circle)
			)
			(primitives
				(gr_poly
					(pts
						(arc
							(start -0.1778 -0.2794)
							(mid -0.249642 -0.249642)
							(end -0.2794 -0.1778)
						)
						(arc
							(start -0.2794 0.1778)
							(mid -0.249642 0.249642)
							(end -0.1778 0.2794)
						)
						(arc
							(start 0.1778 0.2794)
							(mid 0.249642 0.249642)
							(end 0.2794 0.1778)
						)
						(arc
							(start 0.2794 -0.1778)
							(mid 0.249642 -0.249642)
							(end 0.1778 -0.2794)
						)
					)
					(width 0)
					(fill yes)
				)
			)
		)
	)
	(footprint ""
		(layer "F.Cu")
		(at 66.04 -163.322 -90)
		(property "Reference" "R76"
			(at 0 0 270)
			(layer "F.SilkS")
			(hide yes)
			(effects
				(font
					(size 1.27 1.27)
				)
			)
		)
		(property "Value" "47KR2F-GP"
			(at 0.064008 -3.993896 270)
			(unlocked yes)
			(layer "F.Fab")
			(hide yes)
			(effects
				(font
					(size 1.016 1.016)
					(thickness 0.1524)
				)
			)
		)
		(property "Device Type" "R402H16"
			(at 0.064008 -5.517896 270)
			(unlocked yes)
			(layer "F.Fab")
			(hide yes)
			(effects
				(font
					(size 1.016 1.016)
					(thickness 0.1524)
				)
			)
		)
		(duplicate_pad_numbers_are_jumpers no)
		(fp_line
			(start -0.508 -0.9398)
			(end -0.508 0.9398)
			(stroke
				(width 0.1524)
				(type default)
			)
			(layer "F.SilkS")
		)
		(fp_line
			(start 0.508 -0.9398)
			(end -0.508 -0.9398)
			(stroke
				(width 0.1524)
				(type default)
			)
			(layer "F.SilkS")
		)
		(fp_rect
			(start -0.508 0.9398)
			(end 0.508 -0.9398)
			(stroke
				(width 0)
				(type default)
			)
			(fill no)
			(layer "F.CrtYd")
		)
		(fp_rect
			(start -0.508 0.9398)
			(end 0.508 -0.9398)
			(stroke
				(width 0)
				(type default)
			)
			(fill no)
			(layer "F.Fab")
		)
		(pad "1" smd custom
			(at 0 -0.4445 270)
			(size 0.1397 0.1397)
			(layers "F.Cu" "F.Mask" "F.Paste")
			(net "FM_TPM_PRSNT_RST_N")
			(options
				(clearance outline)
				(anchor circle)
			)
			(primitives
				(gr_poly
					(pts
						(arc
							(start -0.1778 -0.2794)
							(mid -0.249642 -0.249642)
							(end -0.2794 -0.1778)
						)
						(arc
							(start -0.2794 0.1778)
							(mid -0.249642 0.249642)
							(end -0.1778 0.2794)
						)
						(arc
							(start 0.1778 0.2794)
							(mid 0.249642 0.249642)
							(end 0.2794 0.1778)
						)
						(arc
							(start 0.2794 -0.1778)
							(mid 0.249642 -0.249642)
							(end 0.1778 -0.2794)
						)
					)
					(width 0)
					(fill yes)
				)
			)
		)
		(pad "2" smd custom
			(at 0 0.4445 270)
			(size 0.1397 0.1397)
			(layers "F.Cu" "F.Mask" "F.Paste")
			(net "FM_TPM_PRSNT_RST_N_R")
			(options
				(clearance outline)
				(anchor circle)
			)
			(primitives
				(gr_poly
					(pts
						(arc
							(start -0.1778 -0.2794)
							(mid -0.249642 -0.249642)
							(end -0.2794 -0.1778)
						)
						(arc
							(start -0.2794 0.1778)
							(mid -0.249642 0.249642)
							(end -0.1778 0.2794)
						)
						(arc
							(start 0.1778 0.2794)
							(mid 0.249642 0.249642)
							(end 0.2794 0.1778)
						)
						(arc
							(start 0.2794 -0.1778)
							(mid 0.249642 -0.249642)
							(end 0.1778 -0.2794)
						)
					)
					(width 0)
					(fill yes)
				)
			)
		)
	)
	(footprint ""
		(layer "F.Cu")
		(at 94.488 -17.8816)
		(property "Reference" "D19"
			(at 0 0 0)
			(layer "F.SilkS")
			(hide yes)
			(effects
				(font
					(size 1.27 1.27)
				)
			)
		)
		(property "Value" "PESD5V0F1BL-GP"
			(at 1.8923 -1.5621 0)
			(unlocked yes)
			(layer "F.Fab")
			(hide yes)
			(effects
				(font
					(size 1.016 1.016)
					(thickness 0.1524)
				)
			)
		)
		(property "Device Type" "SOD882-10D6-1H20"
			(at 1.8923 -3.0861 0)
			(unlocked yes)
			(layer "F.Fab")
			(hide yes)
			(effects
				(font
					(size 1.016 1.016)
					(thickness 0.1524)
				)
			)
		)
		(duplicate_pad_numbers_are_jumpers no)
		(fp_line
			(start -0.3048 -0.9271)
			(end 0.3048 -0.9271)
			(stroke
				(width 0.254)
				(type default)
			)
			(layer "F.SilkS")
		)
		(fp_rect
			(start -0.2921 0.4953)
			(end 0.2921 -0.4953)
			(stroke
				(width 0)
				(type default)
			)
			(fill no)
			(layer "F.CrtYd")
		)
		(fp_poly
			(pts
				(xy -0.4318 0.8001) (xy -0.4318 -0.266192) (xy -0.2921 -0.266192) (xy -0.2921 0.4953) (xy 0.2921 0.4953)
				(xy 0.2921 -0.4953) (xy -0.2921 -0.4953) (xy -0.2921 -0.2667) (xy -0.4318 -0.2667) (xy -0.4318 -0.8001)
				(xy 0.4318 -0.8001) (xy 0.4318 0.8001)
			)
			(stroke
				(width 0)
				(type default)
			)
			(fill no)
			(layer "F.CrtYd")
		)
		(fp_rect
			(start -0.4318 0.8001)
			(end 0.4318 -0.8001)
			(stroke
				(width 0)
				(type default)
			)
			(fill no)
			(layer "F.Fab")
		)
		(pad "1" smd custom
			(at 0 -0.4445)
			(size 0.1143 0.1143)
			(layers "F.Cu" "F.Mask" "F.Paste")
			(net "GND")
			(options
				(clearance outline)
				(anchor circle)
			)
			(primitives
				(gr_poly
					(pts
						(arc
							(start -0.2032 0.2286)
							(mid -0.275042 0.198842)
							(end -0.3048 0.127)
						)
						(arc
							(start -0.3048 -0.127)
							(mid -0.275042 -0.198842)
							(end -0.2032 -0.2286)
						)
						(arc
							(start 0.2032 -0.2286)
							(mid 0.275042 -0.198842)
							(end 0.3048 -0.127)
						)
						(arc
							(start 0.3048 0.127)
							(mid 0.275042 0.198842)
							(end 0.2032 0.2286)
						)
					)
					(width 0)
					(fill yes)
				)
			)
		)
		(pad "2" smd custom
			(at 0 0.4445)
			(size 0.1143 0.1143)
			(layers "F.Cu" "F.Mask" "F.Paste")
			(net "USB_P1_F_DN1")
			(options
				(clearance outline)
				(anchor circle)
			)
			(primitives
				(gr_poly
					(pts
						(arc
							(start 0.2032 -0.2286)
							(mid 0.275042 -0.198842)
							(end 0.3048 -0.127)
						)
						(arc
							(start 0.3048 0.127)
							(mid 0.275042 0.198842)
							(end 0.2032 0.2286)
						)
						(arc
							(start -0.2032 0.2286)
							(mid -0.275042 0.198842)
							(end -0.3048 0.127)
						)
						(arc
							(start -0.3048 -0.127)
							(mid -0.275042 -0.198842)
							(end -0.2032 -0.2286)
						)
					)
					(width 0)
					(fill yes)
				)
			)
		)
	)
	(footprint ""
		(layer "F.Cu")
		(at 205.2828 -111.5568 180)
		(property "Reference" "C509"
			(at 0 0 180)
			(layer "F.SilkS")
			(hide yes)
			(effects
				(font
					(size 1.27 1.27)
				)
			)
		)
		(property "Value" "SE470UF2VDM-GP"
			(at 0 -9.6012 180)
			(unlocked yes)
			(layer "F.Fab")
			(hide yes)
			(effects
				(font
					(size 1.016 1.016)
					(thickness 0.1524)
				)
			)
		)
		(property "Device Type" "CT7343H83"
			(at 0 -11.1252 180)
			(unlocked yes)
			(layer "F.Fab")
			(hide yes)
			(effects
				(font
					(size 1.016 1.016)
					(thickness 0.1524)
				)
			)
		)
		(duplicate_pad_numbers_are_jumpers no)
		(fp_line
			(start 2.286 4.8768)
			(end -2.286 4.8768)
			(stroke
				(width 0.1524)
				(type default)
			)
			(layer "F.SilkS")
		)
		(fp_line
			(start 2.286 2.032)
			(end 2.286 4.8768)
			(stroke
				(width 0.1524)
				(type default)
			)
			(layer "F.SilkS")
		)
		(fp_line
			(start 2.286 -2.032)
			(end 2.286 -4.8768)
			(stroke
				(width 0.1524)
				(type default)
			)
			(layer "F.SilkS")
		)
		(fp_line
			(start 2.286 -4.8768)
			(end -2.286 -4.8768)
			(stroke
				(width 0.1524)
				(type default)
			)
			(layer "F.SilkS")
		)
		(fp_line
			(start 2.1082 -4.699)
			(end -2.1082 -4.699)
			(stroke
				(width 0.508)
				(type default)
			)
			(layer "F.SilkS")
		)
		(fp_line
			(start -2.286 4.8768)
			(end -2.286 2.032)
			(stroke
				(width 0.1524)
				(type default)
			)
			(layer "F.SilkS")
		)
		(fp_line
			(start -2.286 -4.8768)
			(end -2.286 -2.032)
			(stroke
				(width 0.1524)
				(type default)
			)
			(layer "F.SilkS")
		)
		(fp_rect
			(start -2.1463 3.6449)
			(end 2.1463 -3.6449)
			(stroke
				(width 0)
				(type default)
			)
			(fill no)
			(layer "F.CrtYd")
		)
		(fp_poly
			(pts
				(xy -2.54 4.953) (xy -2.54 4.2926) (xy -3.81 4.2926) (xy -3.81 -4.2926) (xy -2.54 -4.2926) (xy -2.54 -4.953)
				(xy 2.54 -4.953) (xy 2.54 -4.2926) (xy 3.81 -4.2926) (xy 3.81 -1.6256) (xy 2.1463 -1.6256) (xy 2.1463 -3.6449)
				(xy -2.1463 -3.6449) (xy -2.1463 3.6449) (xy 2.1463 3.6449) (xy 2.1463 -1.6129) (xy 3.81 -1.6129)
				(xy 3.81 4.2926) (xy 2.54 4.2926) (xy 2.54 4.953)
			)
			(stroke
				(width 0)
				(type default)
			)
			(fill no)
			(layer "F.CrtYd")
		)
		(fp_rect
			(start 2.54 4.2926)
			(end 3.81 -4.2926)
			(stroke
				(width 0)
				(type default)
			)
			(fill no)
			(layer "F.Fab")
		)
		(fp_rect
			(start -2.54 4.953)
			(end 2.54 -4.953)
			(stroke
				(width 0)
				(type default)
			)
			(fill no)
			(layer "F.Fab")
		)
		(fp_rect
			(start -3.81 4.2926)
			(end -2.54 -4.2926)
			(stroke
				(width 0)
				(type default)
			)
			(fill no)
			(layer "F.Fab")
		)
		(pad "1" smd rect
			(at 0 -3.1496 180)
			(size 2.413 2.286)
			(layers "F.Cu" "F.Mask" "F.Paste")
			(net "P0V975")
		)
		(pad "2" smd rect
			(at 0 3.1496 180)
			(size 2.413 2.286)
			(layers "F.Cu" "F.Mask" "F.Paste")
			(net "GND")
		)
		(zone
			(layer "F.Cu")
			(hatch none 0.5)
			(connect_pads
				(clearance 0)
			)
			(min_thickness 0.25)
			(keepout
				(tracks allowed)
				(vias not_allowed)
				(pads allowed)
				(copperpour not_allowed)
				(footprints allowed)
			)
			(placement
				(enabled no)
				(sheetname "")
			)
			(fill
				(thermal_gap 0.5)
				(thermal_bridge_width 0.5)
				(island_removal_mode 0)
			)
			(polygon
				(pts
					(xy 203.7715 -109.8677) (xy 203.7715 -106.9594) (xy 206.7941 -106.9594) (xy 206.7941 -109.855)
					(xy 206.7941 -110.1852) (xy 203.7715 -110.1852)
				)
			)
		)
		(zone
			(layer "F.Cu")
			(hatch none 0.5)
			(connect_pads
				(clearance 0)
			)
			(min_thickness 0.25)
			(keepout
				(tracks allowed)
				(vias not_allowed)
				(pads allowed)
				(copperpour not_allowed)
				(footprints allowed)
			)
			(placement
				(enabled no)
				(sheetname "")
			)
			(fill
				(thermal_gap 0.5)
				(thermal_bridge_width 0.5)
				(island_removal_mode 0)
			)
			(polygon
				(pts
					(xy 206.7941 -116.1542) (xy 203.7715 -116.1542) (xy 203.7715 -113.2586) (xy 203.7715 -112.9284)
					(xy 206.7941 -112.9284) (xy 206.7941 -113.2586)
				)
			)
		)
	)
	(footprint ""
		(layer "F.Cu")
		(at 66.044826 -168.201086 90)
		(property "Reference" "R80"
			(at 0 0 90)
			(layer "F.SilkS")
			(hide yes)
			(effects
				(font
					(size 1.27 1.27)
				)
			)
		)
		(property "Value" "100KR2F-L1-GP"
			(at 0.064008 -3.993896 90)
			(unlocked yes)
			(layer "F.Fab")
			(hide yes)
			(effects
				(font
					(size 1.016 1.016)
					(thickness 0.1524)
				)
			)
		)
		(property "Device Type" "R402H16"
			(at 0.064008 -5.517896 90)
			(unlocked yes)
			(layer "F.Fab")
			(hide yes)
			(effects
				(font
					(size 1.016 1.016)
					(thickness 0.1524)
				)
			)
		)
		(duplicate_pad_numbers_are_jumpers no)
		(fp_line
			(start 0.508 -0.9398)
			(end -0.508 -0.9398)
			(stroke
				(width 0.1524)
				(type default)
			)
			(layer "F.SilkS")
		)
		(fp_line
			(start -0.508 -0.9398)
			(end -0.508 0.9398)
			(stroke
				(width 0.1524)
				(type default)
			)
			(layer "F.SilkS")
		)
		(fp_rect
			(start -0.508 0.9398)
			(end 0.508 -0.9398)
			(stroke
				(width 0)
				(type default)
			)
			(fill no)
			(layer "F.CrtYd")
		)
		(fp_rect
			(start -0.508 0.9398)
			(end 0.508 -0.9398)
			(stroke
				(width 0)
				(type default)
			)
			(fill no)
			(layer "F.Fab")
		)
		(pad "1" smd custom
			(at 0 -0.4445 90)
			(size 0.1397 0.1397)
			(layers "F.Cu" "F.Mask" "F.Paste")
			(net "Q4_G")
			(options
				(clearance outline)
				(anchor circle)
			)
			(primitives
				(gr_poly
					(pts
						(arc
							(start -0.1778 -0.2794)
							(mid -0.249642 -0.249642)
							(end -0.2794 -0.1778)
						)
						(arc
							(start -0.2794 0.1778)
							(mid -0.249642 0.249642)
							(end -0.1778 0.2794)
						)
						(arc
							(start 0.1778 0.2794)
							(mid 0.249642 0.249642)
							(end 0.2794 0.1778)
						)
						(arc
							(start 0.2794 -0.1778)
							(mid 0.249642 -0.249642)
							(end 0.1778 -0.2794)
						)
					)
					(width 0)
					(fill yes)
				)
			)
		)
		(pad "2" smd custom
			(at 0 0.4445 90)
			(size 0.1397 0.1397)
			(layers "F.Cu" "F.Mask" "F.Paste")
			(net "GND")
			(options
				(clearance outline)
				(anchor circle)
			)
			(primitives
				(gr_poly
					(pts
						(arc
							(start -0.1778 -0.2794)
							(mid -0.249642 -0.249642)
							(end -0.2794 -0.1778)
						)
						(arc
							(start -0.2794 0.1778)
							(mid -0.249642 0.249642)
							(end -0.1778 0.2794)
						)
						(arc
							(start 0.1778 0.2794)
							(mid 0.249642 0.249642)
							(end 0.2794 0.1778)
						)
						(arc
							(start 0.2794 -0.1778)
							(mid 0.249642 -0.249642)
							(end 0.1778 -0.2794)
						)
					)
					(width 0)
					(fill yes)
				)
			)
		)
	)
	(footprint ""
		(layer "F.Cu")
		(at 172.5168 -144.1196 -90)
		(property "Reference" "C154"
			(at 0 0 270)
			(layer "F.SilkS")
			(hide yes)
			(effects
				(font
					(size 1.27 1.27)
				)
			)
		)
		(property "Value" "SC10U16V5KX-7-GP-U"
			(at -0.0762 -6.1214 270)
			(unlocked yes)
			(layer "F.Fab")
			(hide yes)
			(effects
				(font
					(size 1.016 1.016)
					(thickness 0.1524)
				)
			)
		)
		(property "Device Type" "C805H58"
			(at -0.0762 -8.1534 270)
			(unlocked yes)
			(layer "F.Fab")
			(hide yes)
			(effects
				(font
					(size 1.016 1.016)
					(thickness 0.1524)
				)
			)
		)
		(duplicate_pad_numbers_are_jumpers no)
		(fp_line
			(start 0.635 0)
			(end -0.635 0)
			(stroke
				(width 0.508)
				(type default)
			)
			(layer "F.SilkS")
		)
		(fp_rect
			(start -0.9652 1.778)
			(end 0.9652 -1.778)
			(stroke
				(width 0)
				(type default)
			)
			(fill no)
			(layer "F.CrtYd")
		)
		(fp_poly
			(pts
				(xy -0.9652 -1.778) (xy 0.9652 -1.778) (xy 0.9652 1.778) (xy -0.9652 1.778)
			)
			(stroke
				(width 0)
				(type default)
			)
			(fill no)
			(layer "F.Fab")
		)
		(pad "1" smd rect
			(at 0 -0.9652 270)
			(size 1.397 1.143)
			(layers "F.Cu" "F.Mask" "F.Paste")
			(net "P12V_STBY_VIN_PU1")
		)
		(pad "2" smd rect
			(at 0 0.9652 270)
			(size 1.397 1.143)
			(layers "F.Cu" "F.Mask" "F.Paste")
			(net "GND")
		)
	)
	(footprint ""
		(layer "F.Cu")
		(at 51.45024 -158.944564 180)
		(property "Reference" "R297"
			(at 0 0 180)
			(layer "F.SilkS")
			(hide yes)
			(effects
				(font
					(size 1.27 1.27)
				)
			)
		)
		(property "Value" "0R2J-2-GP"
			(at 0.064008 -3.993896 180)
			(unlocked yes)
			(layer "F.Fab")
			(hide yes)
			(effects
				(font
					(size 1.016 1.016)
					(thickness 0.1524)
				)
			)
		)
		(property "Device Type" "R402H16"
			(at 0.064008 -5.517896 180)
			(unlocked yes)
			(layer "F.Fab")
			(hide yes)
			(effects
				(font
					(size 1.016 1.016)
					(thickness 0.1524)
				)
			)
		)
		(duplicate_pad_numbers_are_jumpers no)
		(fp_line
			(start 0.508 -0.9398)
			(end -0.508 -0.9398)
			(stroke
				(width 0.1524)
				(type default)
			)
			(layer "F.SilkS")
		)
		(fp_line
			(start -0.508 -0.9398)
			(end -0.508 0.9398)
			(stroke
				(width 0.1524)
				(type default)
			)
			(layer "F.SilkS")
		)
		(fp_rect
			(start -0.508 0.9398)
			(end 0.508 -0.9398)
			(stroke
				(width 0)
				(type default)
			)
			(fill no)
			(layer "F.CrtYd")
		)
		(fp_rect
			(start -0.508 0.9398)
			(end 0.508 -0.9398)
			(stroke
				(width 0)
				(type default)
			)
			(fill no)
			(layer "F.Fab")
		)
		(pad "1" smd custom
			(at 0 -0.4445 180)
			(size 0.1397 0.1397)
			(layers "F.Cu" "F.Mask" "F.Paste")
			(net "UART_BMC_R_TX")
			(options
				(clearance outline)
				(anchor circle)
			)
			(primitives
				(gr_poly
					(pts
						(arc
							(start -0.1778 -0.2794)
							(mid -0.249642 -0.249642)
							(end -0.2794 -0.1778)
						)
						(arc
							(start -0.2794 0.1778)
							(mid -0.249642 0.249642)
							(end -0.1778 0.2794)
						)
						(arc
							(start 0.1778 0.2794)
							(mid 0.249642 0.249642)
							(end 0.2794 0.1778)
						)
						(arc
							(start 0.2794 -0.1778)
							(mid 0.249642 -0.249642)
							(end 0.1778 -0.2794)
						)
					)
					(width 0)
					(fill yes)
				)
			)
		)
		(pad "2" smd custom
			(at 0 0.4445 180)
			(size 0.1397 0.1397)
			(layers "F.Cu" "F.Mask" "F.Paste")
			(net "UART_BMC_TX")
			(options
				(clearance outline)
				(anchor circle)
			)
			(primitives
				(gr_poly
					(pts
						(arc
							(start -0.1778 -0.2794)
							(mid -0.249642 -0.249642)
							(end -0.2794 -0.1778)
						)
						(arc
							(start -0.2794 0.1778)
							(mid -0.249642 0.249642)
							(end -0.1778 0.2794)
						)
						(arc
							(start 0.1778 0.2794)
							(mid 0.249642 0.249642)
							(end 0.2794 0.1778)
						)
						(arc
							(start 0.2794 -0.1778)
							(mid 0.249642 -0.249642)
							(end 0.1778 -0.2794)
						)
					)
					(width 0)
					(fill yes)
				)
			)
		)
	)
)
